# T6G (Grand Teton) — schematic netlist excerpt (pin names and nets, part order shuffled) for the footprints in the layout excerpt that follows; sources: Cadence DE-HDL packaged netlist, KiCad conversion of 04192023_DAF0TMB3IC0_F0TG_MB_C_brd_V02_OCP.brd

R3480  Q_RES  33.2 1% CHIP  pkg 0402LF  page 81 : A = GPU_BASE_HMC_READY_ISO_R ; B = GPU_BASE_HMC_READY_ISO
R464  Q_RES  33 5% CHIP  pkg 0402LF  page 29 : A = SPI_CPU0_D0 ; B = SPI_CPU0_R_D0

(kicad_pcb
	(version 20260206)
	(generator "pcbnew")
	(generator_version "10.0")
	(general
		(thickness 1.6)
		(legacy_teardrops no)
	)
	(paper "A4")
	(title_block
		(title "04192023_DAF0TMB3IC0_F0TG_MB_C_brd_V02_OCP.brd")
		(comment 1 "Grand Teton / footprints 1578-1579 of 8354")
	)
	(layers
		(0 "F.Cu" signal "TOP")
		(4 "In1.Cu" signal "GND")
		(6 "In2.Cu" signal "IN1")
		(8 "In3.Cu" signal "GND1")
		(10 "In4.Cu" signal "IN2")
		(12 "In5.Cu" signal "GND2")
		(14 "In6.Cu" signal "IN3")
		(16 "In7.Cu" signal "GND3")
		(18 "In8.Cu" signal "VCC")
		(20 "In9.Cu" signal "VCC1")
		(22 "In10.Cu" signal "GND4")
		(24 "In11.Cu" signal "IN4")
		(26 "In12.Cu" signal "GND5")
		(28 "In13.Cu" signal "IN5")
		(30 "In14.Cu" signal "GND6")
		(32 "In15.Cu" signal "IN6")
		(34 "In16.Cu" signal "GND7")
		(2 "B.Cu" signal "BOTTOM")
		(9 "F.Adhes" user "F.Adhesive")
		(11 "B.Adhes" user "B.Adhesive")
		(13 "F.Paste" user "Package Geometry/Pastemask Top")
		(15 "B.Paste" user "Package Geometry/Pastemask Bottom")
		(5 "F.SilkS" user "Ref Des/Silkscreen Top")
		(7 "B.SilkS" user "Ref Des/Silkscreen Bottom")
		(1 "F.Mask" user "Board Geometry/Soldermask Top")
		(3 "B.Mask" user "Board Geometry/Soldermask Bottom")
		(17 "Dwgs.User" user "User.Drawings")
		(19 "Cmts.User" user "User.Comments")
		(21 "Eco1.User" user "User.Eco1")
		(23 "Eco2.User" user "User.Eco2")
		(25 "Edge.Cuts" user "Board Geometry/Outline")
		(27 "Margin" user)
		(31 "F.CrtYd" user "Package Geometry/Place Bound Top")
		(29 "B.CrtYd" user "Package Geometry/Place Bound Bottom")
		(35 "F.Fab" user "Ref Des/Assembly Top")
		(33 "B.Fab" user "Ref Des/Assembly Bottom")
	)
	(footprint ""
		(layer "F.Cu")
		(at 396.125192 -330.862686 180)
		(property "Reference" "R464"
			(at 0 0 180)
			(layer "F.SilkS")
			(hide yes)
			(effects
				(font
					(size 1.27 1.27)
				)
			)
		)
		(property "Value" ""
			(at 0 0 180)
			(layer "F.Fab")
			(effects
				(font
					(size 1.27 1.27)
				)
			)
		)
		(duplicate_pad_numbers_are_jumpers no)
		(fp_line
			(start 0.7874 0.4064)
			(end -0.7874 0.4064)
			(stroke
				(width 0.1524)
				(type default)
			)
			(layer "F.SilkS")
		)
		(fp_line
			(start 0.7874 -0.4064)
			(end 0.7874 0.4064)
			(stroke
				(width 0.1524)
				(type default)
			)
			(layer "F.SilkS")
		)
		(fp_line
			(start -0.7874 0.4064)
			(end -0.7874 -0.4064)
			(stroke
				(width 0.1524)
				(type default)
			)
			(layer "F.SilkS")
		)
		(fp_line
			(start -0.7874 -0.4064)
			(end 0.7874 -0.4064)
			(stroke
				(width 0.1524)
				(type default)
			)
			(layer "F.SilkS")
		)
		(fp_line
			(start 0.67945 0.3048)
			(end 0.120396 0.3048)
			(stroke
				(width 0.1)
				(type default)
			)
			(layer "F.Fab")
		)
		(fp_line
			(start 0.67945 -0.3048)
			(end 0.67945 0.3048)
			(stroke
				(width 0.1)
				(type default)
			)
			(layer "F.Fab")
		)
		(fp_line
			(start 0.12065 -0.2794)
			(end 0.12065 -0.3048)
			(stroke
				(width 0.1)
				(type default)
			)
			(layer "F.Fab")
		)
		(fp_line
			(start 0.12065 -0.3048)
			(end 0.67945 -0.3048)
			(stroke
				(width 0.1)
				(type default)
			)
			(layer "F.Fab")
		)
		(fp_line
			(start 0.120396 0.3048)
			(end 0.120396 0.2794)
			(stroke
				(width 0.1)
				(type default)
			)
			(layer "F.Fab")
		)
		(fp_line
			(start 0.120396 0.2794)
			(end -0.12065 0.2794)
			(stroke
				(width 0.1)
				(type default)
			)
			(layer "F.Fab")
		)
		(fp_line
			(start -0.12065 0.3048)
			(end -0.67945 0.3048)
			(stroke
				(width 0.1)
				(type default)
			)
			(layer "F.Fab")
		)
		(fp_line
			(start -0.12065 0.2794)
			(end -0.12065 0.3048)
			(stroke
				(width 0.1)
				(type default)
			)
			(layer "F.Fab")
		)
		(fp_line
			(start -0.12065 -0.2794)
			(end 0.12065 -0.2794)
			(stroke
				(width 0.1)
				(type default)
			)
			(layer "F.Fab")
		)
		(fp_line
			(start -0.12065 -0.305054)
			(end -0.12065 -0.2794)
			(stroke
				(width 0.1)
				(type default)
			)
			(layer "F.Fab")
		)
		(fp_line
			(start -0.67945 0.3048)
			(end -0.67945 -0.305054)
			(stroke
				(width 0.1)
				(type default)
			)
			(layer "F.Fab")
		)
		(fp_line
			(start -0.67945 -0.305054)
			(end -0.12065 -0.305054)
			(stroke
				(width 0.1)
				(type default)
			)
			(layer "F.Fab")
		)
		(pad "1" smd circle
			(at -0.40005 0 180)
			(size 0 0)
			(layers "F.Cu" "F.Mask" "F.Paste")
			(net "SPI_CPU0_D0")
		)
		(pad "2" smd circle
			(at 0.40005 0 180)
			(size 0 0)
			(layers "F.Cu" "F.Mask" "F.Paste")
			(net "SPI_CPU0_R_D0")
		)
	)
	(footprint ""
		(layer "F.Cu")
		(at 205.181708 -117.748812)
		(property "Reference" "R3480"
			(at 0 0 0)
			(layer "F.SilkS")
			(hide yes)
			(effects
				(font
					(size 1.27 1.27)
				)
			)
		)
		(property "Value" ""
			(at 0 0 0)
			(layer "F.Fab")
			(effects
				(font
					(size 1.27 1.27)
				)
			)
		)
		(duplicate_pad_numbers_are_jumpers no)
		(fp_line
			(start -0.7874 -0.4064)
			(end 0.7874 -0.4064)
			(stroke
				(width 0.1524)
				(type default)
			)
			(layer "F.SilkS")
		)
		(fp_line
			(start -0.7874 0.4064)
			(end -0.7874 -0.4064)
			(stroke
				(width 0.1524)
				(type default)
			)
			(layer "F.SilkS")
		)
		(fp_line
			(start 0.7874 -0.4064)
			(end 0.7874 0.4064)
			(stroke
				(width 0.1524)
				(type default)
			)
			(layer "F.SilkS")
		)
		(fp_line
			(start 0.7874 0.4064)
			(end -0.7874 0.4064)
			(stroke
				(width 0.1524)
				(type default)
			)
			(layer "F.SilkS")
		)
		(fp_line
			(start -0.67945 -0.305054)
			(end -0.12065 -0.305054)
			(stroke
				(width 0.1)
				(type default)
			)
			(layer "F.Fab")
		)
		(fp_line
			(start -0.67945 0.3048)
			(end -0.67945 -0.305054)
			(stroke
				(width 0.1)
				(type default)
			)
			(layer "F.Fab")
		)
		(fp_line
			(start -0.12065 -0.305054)
			(end -0.12065 -0.2794)
			(stroke
				(width 0.1)
				(type default)
			)
			(layer "F.Fab")
		)
		(fp_line
			(start -0.12065 -0.2794)
			(end 0.12065 -0.2794)
			(stroke
				(width 0.1)
				(type default)
			)
			(layer "F.Fab")
		)
		(fp_line
			(start -0.12065 0.2794)
			(end -0.12065 0.3048)
			(stroke
				(width 0.1)
				(type default)
			)
			(layer "F.Fab")
		)
		(fp_line
			(start -0.12065 0.3048)
			(end -0.67945 0.3048)
			(stroke
				(width 0.1)
				(type default)
			)
			(layer "F.Fab")
		)
		(fp_line
			(start 0.120396 0.2794)
			(end -0.12065 0.2794)
			(stroke
				(width 0.1)
				(type default)
			)
			(layer "F.Fab")
		)
		(fp_line
			(start 0.120396 0.3048)
			(end 0.120396 0.2794)
			(stroke
				(width 0.1)
				(type default)
			)
			(layer "F.Fab")
		)
		(fp_line
			(start 0.12065 -0.3048)
			(end 0.67945 -0.3048)
			(stroke
				(width 0.1)
				(type default)
			)
			(layer "F.Fab")
		)
		(fp_line
			(start 0.12065 -0.2794)
			(end 0.12065 -0.3048)
			(stroke
				(width 0.1)
				(type default)
			)
			(layer "F.Fab")
		)
		(fp_line
			(start 0.67945 -0.3048)
			(end 0.67945 0.3048)
			(stroke
				(width 0.1)
				(type default)
			)
			(layer "F.Fab")
		)
		(fp_line
			(start 0.67945 0.3048)
			(end 0.120396 0.3048)
			(stroke
				(width 0.1)
				(type default)
			)
			(layer "F.Fab")
		)
		(pad "1" smd circle
			(at -0.40005 0)
			(size 0 0)
			(layers "F.Cu" "F.Mask" "F.Paste")
			(net "GPU_BASE_HMC_READY_ISO_R")
		)
		(pad "2" smd circle
			(at 0.40005 0)
			(size 0 0)
			(layers "F.Cu" "F.Mask" "F.Paste")
			(net "GPU_BASE_HMC_READY_ISO")
		)
	)
)
